(kicad_pcb
	(version 20241229)
	(generator "pcbnew")
	(generator_version "9.0")
	(general
		(thickness 1.599998)
		(legacy_teardrops no)
	)
	(paper "A4")
	(title_block
		(title "Artix - Datacenter Secure Control Module (DC-SCM)")
		(date "2024-11-06")
		(rev "1.1.3")
		(comment 9 "footprints 490-495 of 544")
	)
	(layers
		(0 "F.Cu" signal)
		(4 "In1.Cu" signal)
		(6 "In2.Cu" signal)
		(8 "In3.Cu" signal)
		(10 "In4.Cu" signal)
		(12 "In5.Cu" signal)
		(14 "In6.Cu" signal)
		(2 "B.Cu" signal)
		(9 "F.Adhes" user "F.Adhesive")
		(11 "B.Adhes" user "B.Adhesive")
		(13 "F.Paste" user)
		(15 "B.Paste" user)
		(5 "F.SilkS" user "F.Silkscreen")
		(7 "B.SilkS" user "B.Silkscreen")
		(1 "F.Mask" user)
		(3 "B.Mask" user)
		(17 "Dwgs.User" user "User.Drawings")
		(19 "Cmts.User" user "User.Comments")
		(21 "Eco1.User" user "User.Eco1")
		(23 "Eco2.User" user "User.Eco2")
		(25 "Edge.Cuts" user)
		(27 "Margin" user)
		(31 "F.CrtYd" user "F.Courtyard")
		(29 "B.CrtYd" user "B.Courtyard")
		(35 "F.Fab" user)
		(33 "B.Fab" user)
	)
	(footprint "antmicro-footprints:R_0402_1005Metric"
		(layer "B.Cu")
		(at 103.175 141.875 90)
		(descr "Resistor SMD 0402")
		(tags "resistor SMD 0402")
		(property "Reference" "R179"
			(at 0.775 0.425 90)
			(layer "B.SilkS")
			(effects
				(font
					(size 0.7 0.7)
					(thickness 0.15)
				)
				(justify right bottom mirror)
			)
		)
		(property "Value" "R_51R_0402"
			(at 0 -1.4 90)
			(layer "B.Fab")
			(effects
				(font
					(size 0.7 0.7)
					(thickness 0.15)
				)
				(justify right bottom mirror)
			)
		)
		(property "Datasheet" "https://www.bourns.com/docs/product-datasheets/cr.pdf"
			(at 0 0 90)
			(layer "F.Fab")
			(hide yes)
			(effects
				(font
					(size 1.27 1.27)
					(thickness 0.15)
				)
			)
		)
		(property "Description" "SMD Chip Resistor, 51 ohm, ± 1%, 63 mW, 0402 [1005 Metric], Thick Film, General Purpose"
			(at 0 0 90)
			(layer "F.Fab")
			(hide yes)
			(effects
				(font
					(size 1.27 1.27)
					(thickness 0.15)
				)
			)
		)
		(property "Author" "Antmicro"
			(at 245.05 38.7 0)
			(layer "B.Fab")
			(hide yes)
			(effects
				(font
					(size 1 1)
					(thickness 0.15)
				)
				(justify mirror)
			)
		)
		(property "License" "Apache-2.0"
			(at 245.05 38.7 0)
			(layer "B.Fab")
			(hide yes)
			(effects
				(font
					(size 1 1)
					(thickness 0.15)
				)
				(justify mirror)
			)
		)
		(property "MPN" "CR0402-FX-51R0GLF"
			(at 245.05 38.7 0)
			(layer "B.Fab")
			(hide yes)
			(effects
				(font
					(size 1 1)
					(thickness 0.15)
				)
				(justify mirror)
			)
		)
		(property "Manufacturer" "Bourns"
			(at 245.05 38.7 0)
			(layer "B.Fab")
			(hide yes)
			(effects
				(font
					(size 1 1)
					(thickness 0.15)
				)
				(justify mirror)
			)
		)
		(property "Tolerance" "1%"
			(at 245.05 38.7 0)
			(layer "B.Fab")
			(hide yes)
			(effects
				(font
					(size 1 1)
					(thickness 0.15)
				)
				(justify mirror)
			)
		)
		(property "Val" "51R"
			(at 245.05 38.7 0)
			(layer "B.Fab")
			(hide yes)
			(effects
				(font
					(size 1 1)
					(thickness 0.15)
				)
				(justify mirror)
			)
		)
		(sheetname "/DDR3/")
		(sheetfile "ddr3.kicad_sch")
		(attr smd exclude_from_pos_files exclude_from_bom dnp)
		(fp_rect
			(start -0.925 0.47)
			(end 0.925 -0.47)
			(stroke
				(width 0.05)
				(type default)
			)
			(fill no)
			(layer "B.CrtYd")
		)
		(fp_rect
			(start -0.5 0.25)
			(end 0.5 -0.25)
			(stroke
				(width 0.15)
				(type solid)
			)
			(fill no)
			(layer "B.Fab")
		)
		(pad "1" smd roundrect
			(at -0.48 0 90)
			(size 0.59 0.64)
			(layers "B.Cu" "B.Mask" "B.Paste")
			(roundrect_rratio 0.25)
			(net 146 "DDR3_A6")
			(pintype "passive")
		)
		(pad "2" smd roundrect
			(at 0.48 0 90)
			(size 0.59 0.64)
			(layers "B.Cu" "B.Mask" "B.Paste")
			(roundrect_rratio 0.25)
			(net 143 "/DDR3/DDR3_VTT")
			(pintype "passive")
		)
	)
	(footprint "antmicro-footprints:R_0402_1005Metric"
		(layer "B.Cu")
		(at 101.175 141.075 90)
		(descr "Resistor SMD 0402")
		(tags "resistor SMD 0402")
		(property "Reference" "R181"
			(at 0.775 0.425 90)
			(layer "B.SilkS")
			(effects
				(font
					(size 0.7 0.7)
					(thickness 0.15)
				)
				(justify right bottom mirror)
			)
		)
		(property "Value" "R_51R_0402"
			(at 0 -1.4 90)
			(layer "B.Fab")
			(effects
				(font
					(size 0.7 0.7)
					(thickness 0.15)
				)
				(justify right bottom mirror)
			)
		)
		(property "Datasheet" "https://www.bourns.com/docs/product-datasheets/cr.pdf"
			(at 0 0 90)
			(layer "F.Fab")
			(hide yes)
			(effects
				(font
					(size 1.27 1.27)
					(thickness 0.15)
				)
			)
		)
		(property "Description" "SMD Chip Resistor, 51 ohm, ± 1%, 63 mW, 0402 [1005 Metric], Thick Film, General Purpose"
			(at 0 0 90)
			(layer "F.Fab")
			(hide yes)
			(effects
				(font
					(size 1.27 1.27)
					(thickness 0.15)
				)
			)
		)
		(property "Author" "Antmicro"
			(at 242.25 39.9 0)
			(layer "B.Fab")
			(hide yes)
			(effects
				(font
					(size 1 1)
					(thickness 0.15)
				)
				(justify mirror)
			)
		)
		(property "License" "Apache-2.0"
			(at 242.25 39.9 0)
			(layer "B.Fab")
			(hide yes)
			(effects
				(font
					(size 1 1)
					(thickness 0.15)
				)
				(justify mirror)
			)
		)
		(property "MPN" "CR0402-FX-51R0GLF"
			(at 242.25 39.9 0)
			(layer "B.Fab")
			(hide yes)
			(effects
				(font
					(size 1 1)
					(thickness 0.15)
				)
				(justify mirror)
			)
		)
		(property "Manufacturer" "Bourns"
			(at 242.25 39.9 0)
			(layer "B.Fab")
			(hide yes)
			(effects
				(font
					(size 1 1)
					(thickness 0.15)
				)
				(justify mirror)
			)
		)
		(property "Tolerance" "1%"
			(at 242.25 39.9 0)
			(layer "B.Fab")
			(hide yes)
			(effects
				(font
					(size 1 1)
					(thickness 0.15)
				)
				(justify mirror)
			)
		)
		(property "Val" "51R"
			(at 242.25 39.9 0)
			(layer "B.Fab")
			(hide yes)
			(effects
				(font
					(size 1 1)
					(thickness 0.15)
				)
				(justify mirror)
			)
		)
		(sheetname "/DDR3/")
		(sheetfile "ddr3.kicad_sch")
		(attr smd exclude_from_pos_files exclude_from_bom dnp)
		(fp_rect
			(start -0.925 0.47)
			(end 0.925 -0.47)
			(stroke
				(width 0.05)
				(type default)
			)
			(fill no)
			(layer "B.CrtYd")
		)
		(fp_rect
			(start -0.5 0.25)
			(end 0.5 -0.25)
			(stroke
				(width 0.15)
				(type solid)
			)
			(fill no)
			(layer "B.Fab")
		)
		(pad "1" smd roundrect
			(at -0.48 0 90)
			(size 0.59 0.64)
			(layers "B.Cu" "B.Mask" "B.Paste")
			(roundrect_rratio 0.25)
			(net 155 "DDR3_BA1")
			(pintype "passive")
		)
		(pad "2" smd roundrect
			(at 0.48 0 90)
			(size 0.59 0.64)
			(layers "B.Cu" "B.Mask" "B.Paste")
			(roundrect_rratio 0.25)
			(net 143 "/DDR3/DDR3_VTT")
			(pintype "passive")
		)
	)
	(footprint "antmicro-footprints:R_0402_1005Metric"
		(layer "B.Cu")
		(at 99.075 144.775)
		(descr "Resistor SMD 0402")
		(tags "resistor SMD 0402")
		(property "Reference" "R182"
			(at -11.875 -2.775 0)
			(layer "B.SilkS")
			(effects
				(font
					(size 0.7 0.7)
					(thickness 0.15)
				)
				(justify right bottom mirror)
			)
		)
		(property "Value" "R_51R_0402"
			(at 0 -1.4 0)
			(layer "B.Fab")
			(effects
				(font
					(size 0.7 0.7)
					(thickness 0.15)
				)
				(justify right bottom mirror)
			)
		)
		(property "Datasheet" "https://www.bourns.com/docs/product-datasheets/cr.pdf"
			(at 0 0 0)
			(layer "F.Fab")
			(hide yes)
			(effects
				(font
					(size 1.27 1.27)
					(thickness 0.15)
				)
			)
		)
		(property "Description" "SMD Chip Resistor, 51 ohm, ± 1%, 63 mW, 0402 [1005 Metric], Thick Film, General Purpose"
			(at 0 0 0)
			(layer "F.Fab")
			(hide yes)
			(effects
				(font
					(size 1.27 1.27)
					(thickness 0.15)
				)
			)
		)
		(property "Author" "Antmicro"
			(at 0 0 0)
			(layer "B.Fab")
			(hide yes)
			(effects
				(font
					(size 1 1)
					(thickness 0.15)
				)
				(justify mirror)
			)
		)
		(property "License" "Apache-2.0"
			(at 0 0 0)
			(layer "B.Fab")
			(hide yes)
			(effects
				(font
					(size 1 1)
					(thickness 0.15)
				)
				(justify mirror)
			)
		)
		(property "MPN" "CR0402-FX-51R0GLF"
			(at 0 0 0)
			(layer "B.Fab")
			(hide yes)
			(effects
				(font
					(size 1 1)
					(thickness 0.15)
				)
				(justify mirror)
			)
		)
		(property "Manufacturer" "Bourns"
			(at 0 0 0)
			(layer "B.Fab")
			(hide yes)
			(effects
				(font
					(size 1 1)
					(thickness 0.15)
				)
				(justify mirror)
			)
		)
		(property "Tolerance" "1%"
			(at 0 0 0)
			(layer "B.Fab")
			(hide yes)
			(effects
				(font
					(size 1 1)
					(thickness 0.15)
				)
				(justify mirror)
			)
		)
		(property "Val" "51R"
			(at 0 0 0)
			(layer "B.Fab")
			(hide yes)
			(effects
				(font
					(size 1 1)
					(thickness 0.15)
				)
				(justify mirror)
			)
		)
		(sheetname "/DDR3/")
		(sheetfile "ddr3.kicad_sch")
		(attr smd exclude_from_pos_files exclude_from_bom dnp)
		(fp_rect
			(start -0.925 0.47)
			(end 0.925 -0.47)
			(stroke
				(width 0.05)
				(type default)
			)
			(fill no)
			(layer "B.CrtYd")
		)
		(fp_rect
			(start -0.5 0.25)
			(end 0.5 -0.25)
			(stroke
				(width 0.15)
				(type solid)
			)
			(fill no)
			(layer "B.Fab")
		)
		(pad "1" smd roundrect
			(at -0.48 0)
			(size 0.59 0.64)
			(layers "B.Cu" "B.Mask" "B.Paste")
			(roundrect_rratio 0.25)
			(net 160 "DDR3_CKE")
			(pintype "passive")
		)
		(pad "2" smd roundrect
			(at 0.48 0)
			(size 0.59 0.64)
			(layers "B.Cu" "B.Mask" "B.Paste")
			(roundrect_rratio 0.25)
			(net 143 "/DDR3/DDR3_VTT")
			(pintype "passive")
		)
	)
	(footprint "antmicro-footprints:R_0402_1005Metric"
		(layer "B.Cu")
		(at 99.775 141.475 90)
		(descr "Resistor SMD 0402")
		(tags "resistor SMD 0402")
		(property "Reference" "R183"
			(at 0.775 0.425 90)
			(layer "B.SilkS")
			(effects
				(font
					(size 0.7 0.7)
					(thickness 0.15)
				)
				(justify right bottom mirror)
			)
		)
		(property "Value" "R_51R_0402"
			(at 0 -1.4 90)
			(layer "B.Fab")
			(effects
				(font
					(size 0.7 0.7)
					(thickness 0.15)
				)
				(justify right bottom mirror)
			)
		)
		(property "Datasheet" "https://www.bourns.com/docs/product-datasheets/cr.pdf"
			(at 0 0 90)
			(layer "F.Fab")
			(hide yes)
			(effects
				(font
					(size 1.27 1.27)
					(thickness 0.15)
				)
			)
		)
		(property "Description" "SMD Chip Resistor, 51 ohm, ± 1%, 63 mW, 0402 [1005 Metric], Thick Film, General Purpose"
			(at 0 0 90)
			(layer "F.Fab")
			(hide yes)
			(effects
				(font
					(size 1.27 1.27)
					(thickness 0.15)
				)
			)
		)
		(property "Author" "Antmicro"
			(at 241.25 41.7 0)
			(layer "B.Fab")
			(hide yes)
			(effects
				(font
					(size 1 1)
					(thickness 0.15)
				)
				(justify mirror)
			)
		)
		(property "License" "Apache-2.0"
			(at 241.25 41.7 0)
			(layer "B.Fab")
			(hide yes)
			(effects
				(font
					(size 1 1)
					(thickness 0.15)
				)
				(justify mirror)
			)
		)
		(property "MPN" "CR0402-FX-51R0GLF"
			(at 241.25 41.7 0)
			(layer "B.Fab")
			(hide yes)
			(effects
				(font
					(size 1 1)
					(thickness 0.15)
				)
				(justify mirror)
			)
		)
		(property "Manufacturer" "Bourns"
			(at 241.25 41.7 0)
			(layer "B.Fab")
			(hide yes)
			(effects
				(font
					(size 1 1)
					(thickness 0.15)
				)
				(justify mirror)
			)
		)
		(property "Tolerance" "1%"
			(at 241.25 41.7 0)
			(layer "B.Fab")
			(hide yes)
			(effects
				(font
					(size 1 1)
					(thickness 0.15)
				)
				(justify mirror)
			)
		)
		(property "Val" "51R"
			(at 241.25 41.7 0)
			(layer "B.Fab")
			(hide yes)
			(effects
				(font
					(size 1 1)
					(thickness 0.15)
				)
				(justify mirror)
			)
		)
		(sheetname "/DDR3/")
		(sheetfile "ddr3.kicad_sch")
		(attr smd exclude_from_pos_files exclude_from_bom dnp)
		(fp_rect
			(start -0.925 0.47)
			(end 0.925 -0.47)
			(stroke
				(width 0.05)
				(type default)
			)
			(fill no)
			(layer "B.CrtYd")
		)
		(fp_rect
			(start -0.5 0.25)
			(end 0.5 -0.25)
			(stroke
				(width 0.15)
				(type solid)
			)
			(fill no)
			(layer "B.Fab")
		)
		(pad "1" smd roundrect
			(at -0.48 0 90)
			(size 0.59 0.64)
			(layers "B.Cu" "B.Mask" "B.Paste")
			(roundrect_rratio 0.25)
			(net 154 "DDR3_A10")
			(pintype "passive")
		)
		(pad "2" smd roundrect
			(at 0.48 0 90)
			(size 0.59 0.64)
			(layers "B.Cu" "B.Mask" "B.Paste")
			(roundrect_rratio 0.25)
			(net 143 "/DDR3/DDR3_VTT")
			(pintype "passive")
		)
	)
	(footprint "antmicro-footprints:R_0402_1005Metric"
		(layer "B.Cu")
		(at 101.875 151.675)
		(descr "Resistor SMD 0402")
		(tags "resistor SMD 0402")
		(property "Reference" "R184"
			(at -3.575 0.325 0)
			(layer "B.SilkS")
			(effects
				(font
					(size 0.7 0.7)
					(thickness 0.15)
				)
				(justify right bottom mirror)
			)
		)
		(property "Value" "R_51R_0402"
			(at 0 -1.4 0)
			(layer "B.Fab")
			(effects
				(font
					(size 0.7 0.7)
					(thickness 0.15)
				)
				(justify right bottom mirror)
			)
		)
		(property "Datasheet" "https://www.bourns.com/docs/product-datasheets/cr.pdf"
			(at 0 0 0)
			(layer "F.Fab")
			(hide yes)
			(effects
				(font
					(size 1.27 1.27)
					(thickness 0.15)
				)
			)
		)
		(property "Description" "SMD Chip Resistor, 51 ohm, ± 1%, 63 mW, 0402 [1005 Metric], Thick Film, General Purpose"
			(at 0 0 0)
			(layer "F.Fab")
			(hide yes)
			(effects
				(font
					(size 1.27 1.27)
					(thickness 0.15)
				)
			)
		)
		(property "Author" "Antmicro"
			(at 0 0 0)
			(layer "B.Fab")
			(hide yes)
			(effects
				(font
					(size 1 1)
					(thickness 0.15)
				)
				(justify mirror)
			)
		)
		(property "License" "Apache-2.0"
			(at 0 0 0)
			(layer "B.Fab")
			(hide yes)
			(effects
				(font
					(size 1 1)
					(thickness 0.15)
				)
				(justify mirror)
			)
		)
		(property "MPN" "CR0402-FX-51R0GLF"
			(at 0 0 0)
			(layer "B.Fab")
			(hide yes)
			(effects
				(font
					(size 1 1)
					(thickness 0.15)
				)
				(justify mirror)
			)
		)
		(property "Manufacturer" "Bourns"
			(at 0 0 0)
			(layer "B.Fab")
			(hide yes)
			(effects
				(font
					(size 1 1)
					(thickness 0.15)
				)
				(justify mirror)
			)
		)
		(property "Tolerance" "1%"
			(at 0 0 0)
			(layer "B.Fab")
			(hide yes)
			(effects
				(font
					(size 1 1)
					(thickness 0.15)
				)
				(justify mirror)
			)
		)
		(property "Val" "51R"
			(at 0 0 0)
			(layer "B.Fab")
			(hide yes)
			(effects
				(font
					(size 1 1)
					(thickness 0.15)
				)
				(justify mirror)
			)
		)
		(sheetname "/DDR3/")
		(sheetfile "ddr3.kicad_sch")
		(attr smd exclude_from_pos_files exclude_from_bom dnp)
		(fp_rect
			(start -0.925 0.47)
			(end 0.925 -0.47)
			(stroke
				(width 0.05)
				(type default)
			)
			(fill no)
			(layer "B.CrtYd")
		)
		(fp_rect
			(start -0.5 0.25)
			(end 0.5 -0.25)
			(stroke
				(width 0.15)
				(type solid)
			)
			(fill no)
			(layer "B.Fab")
		)
		(pad "1" smd roundrect
			(at -0.48 0)
			(size 0.59 0.64)
			(layers "B.Cu" "B.Mask" "B.Paste")
			(roundrect_rratio 0.25)
			(net 163 "DDR3_CS")
			(pintype "passive")
		)
		(pad "2" smd roundrect
			(at 0.48 0)
			(size 0.59 0.64)
			(layers "B.Cu" "B.Mask" "B.Paste")
			(roundrect_rratio 0.25)
			(net 143 "/DDR3/DDR3_VTT")
			(pintype "passive")
		)
	)
	(footprint "antmicro-footprints:R_0402_1005Metric"
		(layer "B.Cu")
		(at 94.975 149.675 -90)
		(descr "Resistor SMD 0402")
		(tags "resistor SMD 0402")
		(property "Reference" "R54"
			(at 0.725 -0.425 90)
			(layer "B.SilkS")
			(effects
				(font
					(size 0.7 0.7)
					(thickness 0.15)
				)
				(justify left bottom mirror)
			)
		)
		(property "Value" "R_51R_0402"
			(at 0 -1.4 90)
			(layer "B.Fab")
			(effects
				(font
					(size 0.7 0.7)
					(thickness 0.15)
				)
				(justify left bottom mirror)
			)
		)
		(property "Datasheet" "https://www.bourns.com/docs/product-datasheets/cr.pdf"
			(at 0 0 270)
			(layer "F.Fab")
			(hide yes)
			(effects
				(font
					(size 1.27 1.27)
					(thickness 0.15)
				)
			)
		)
		(property "Description" "SMD Chip Resistor, 51 ohm, ± 1%, 63 mW, 0402 [1005 Metric], Thick Film, General Purpose"
			(at 0 0 270)
			(layer "F.Fab")
			(hide yes)
			(effects
				(font
					(size 1.27 1.27)
					(thickness 0.15)
				)
			)
		)
		(property "Author" "Antmicro"
			(at -54.7 244.65 0)
			(layer "B.Fab")
			(hide yes)
			(effects
				(font
					(size 1 1)
					(thickness 0.15)
				)
				(justify mirror)
			)
		)
		(property "License" "Apache-2.0"
			(at -54.7 244.65 0)
			(layer "B.Fab")
			(hide yes)
			(effects
				(font
					(size 1 1)
					(thickness 0.15)
				)
				(justify mirror)
			)
		)
		(property "MPN" "CR0402-FX-51R0GLF"
			(at -54.7 244.65 0)
			(layer "B.Fab")
			(hide yes)
			(effects
				(font
					(size 1 1)
					(thickness 0.15)
				)
				(justify mirror)
			)
		)
		(property "Manufacturer" "Bourns"
			(at -54.7 244.65 0)
			(layer "B.Fab")
			(hide yes)
			(effects
				(font
					(size 1 1)
					(thickness 0.15)
				)
				(justify mirror)
			)
		)
		(property "Tolerance" "1%"
			(at -54.7 244.65 0)
			(layer "B.Fab")
			(hide yes)
			(effects
				(font
					(size 1 1)
					(thickness 0.15)
				)
				(justify mirror)
			)
		)
		(property "Val" "51R"
			(at -54.7 244.65 0)
			(layer "B.Fab")
			(hide yes)
			(effects
				(font
					(size 1 1)
					(thickness 0.15)
				)
				(justify mirror)
			)
		)
		(sheetname "/DDR3/")
		(sheetfile "ddr3.kicad_sch")
		(attr smd exclude_from_pos_files exclude_from_bom dnp)
		(fp_rect
			(start -0.925 0.47)
			(end 0.925 -0.47)
			(stroke
				(width 0.05)
				(type default)
			)
			(fill no)
			(layer "B.CrtYd")
		)
		(fp_rect
			(start -0.5 0.25)
			(end 0.5 -0.25)
			(stroke
				(width 0.15)
				(type solid)
			)
			(fill no)
			(layer "B.Fab")
		)
		(pad "1" smd roundrect
			(at -0.48 0 270)
			(size 0.59 0.64)
			(layers "B.Cu" "B.Mask" "B.Paste")
			(roundrect_rratio 0.25)
			(net 162 "DDR3_RAS")
			(pintype "passive")
		)
		(pad "2" smd roundrect
			(at 0.48 0 270)
			(size 0.59 0.64)
			(layers "B.Cu" "B.Mask" "B.Paste")
			(roundrect_rratio 0.25)
			(net 143 "/DDR3/DDR3_VTT")
			(pintype "passive")
		)
	)
)
